(kicad_pcb
	(version 20260206)
	(generator "pcbnew")
	(generator_version "10.0")
	(general
		(thickness 1.6)
		(legacy_teardrops no)
	)
	(paper "A4")
	(title_block
		(title "netronome-mezz — pcbd0082-001_rev01_jul9_a.brd")
		(comment 1 "Open CloudServer (Microsoft) / footprints 373-378 of 714")
	)
	(layers
		(0 "F.Cu" signal "TOP")
		(4 "In1.Cu" signal "02_GND")
		(6 "In2.Cu" signal "03_SIG")
		(8 "In3.Cu" signal "04_SIG")
		(10 "In4.Cu" signal "05_GND")
		(12 "In5.Cu" signal "06_PWR1")
		(14 "In6.Cu" signal "07_SIG")
		(16 "In7.Cu" signal "08_SIG")
		(18 "In8.Cu" signal "09_GND")
		(2 "B.Cu" signal "BOTTOM")
		(9 "F.Adhes" user "F.Adhesive")
		(11 "B.Adhes" user "B.Adhesive")
		(13 "F.Paste" user "Package Geometry/Pastemask Top")
		(15 "B.Paste" user "Package Geometry/Pastemask Bottom")
		(5 "F.SilkS" user "Ref Des/Silkscreen Top")
		(7 "B.SilkS" user "Ref Des/Silkscreen Bottom")
		(1 "F.Mask" user "Board Geometry/Soldermask Top")
		(3 "B.Mask" user "Board Geometry/Soldermask Bottom")
		(17 "Dwgs.User" user "User.Drawings")
		(19 "Cmts.User" user "User.Comments")
		(21 "Eco1.User" user "User.Eco1")
		(23 "Eco2.User" user "User.Eco2")
		(25 "Edge.Cuts" user "Board Geometry/Outline")
		(27 "Margin" user)
		(31 "F.CrtYd" user "Package Geometry/Place Bound Top")
		(29 "B.CrtYd" user "Package Geometry/Place Bound Bottom")
		(35 "F.Fab" user "Ref Des/Assembly Top")
		(33 "B.Fab" user "Ref Des/Assembly Bottom")
		(45 "User.4" user "COMPVAL_TYPE_BOTTOM")
	)
	(footprint ""
		(layer "B.Cu")
		(at 2.54 13.716)
		(property "Reference" "U21"
			(at -4.09067 1.27 270)
			(unlocked yes)
			(layer "B.SilkS")
			(effects
				(font
					(size 0.7874 0.5842)
					(thickness 0.127)
				)
				(justify left mirror)
			)
		)
		(property "Value" "*"
			(at 0.4826 -0.148107 0)
			(unlocked yes)
			(layer "B.Fab")
			(hide yes)
			(effects
				(font
					(size 1.27 0.9652)
					(thickness 0.000001)
				)
				(justify left mirror)
			)
		)
		(property "Device Type" "ICSO0128"
			(at 0.4826 -0.148107 0)
			(unlocked yes)
			(layer "B.Fab")
			(hide yes)
			(effects
				(font
					(size 1.27 0.9652)
					(thickness 0.000001)
				)
				(justify left mirror)
			)
		)
		(duplicate_pad_numbers_are_jumpers no)
		(fp_line
			(start -2.159 -1.651)
			(end -2.159 -0.762)
			(stroke
				(width 0.1524)
				(type default)
			)
			(layer "B.SilkS")
		)
		(fp_line
			(start -2.159 1.651)
			(end -2.159 0.762)
			(stroke
				(width 0.1524)
				(type default)
			)
			(layer "B.SilkS")
		)
		(fp_line
			(start -1.778 -1.651)
			(end -2.159 -1.651)
			(stroke
				(width 0.1524)
				(type default)
			)
			(layer "B.SilkS")
		)
		(fp_line
			(start -1.778 1.651)
			(end -2.159 1.651)
			(stroke
				(width 0.1524)
				(type default)
			)
			(layer "B.SilkS")
		)
		(fp_line
			(start 1.778 -1.651)
			(end 2.159 -1.651)
			(stroke
				(width 0.1524)
				(type default)
			)
			(layer "B.SilkS")
		)
		(fp_line
			(start 1.778 1.651)
			(end 2.159 1.143)
			(stroke
				(width 0.1524)
				(type default)
			)
			(layer "B.SilkS")
		)
		(fp_line
			(start 1.778 1.651)
			(end 2.159 1.651)
			(stroke
				(width 0.1524)
				(type default)
			)
			(layer "B.SilkS")
		)
		(fp_line
			(start 2.159 -1.651)
			(end 2.159 -0.762)
			(stroke
				(width 0.1524)
				(type default)
			)
			(layer "B.SilkS")
		)
		(fp_line
			(start 2.159 1.651)
			(end 2.159 0.762)
			(stroke
				(width 0.1524)
				(type default)
			)
			(layer "B.SilkS")
		)
		(fp_circle
			(center 2.032 2.159)
			(end 2.286 2.159)
			(stroke
				(width 0.1524)
				(type default)
			)
			(fill no)
			(layer "B.SilkS")
		)
		(fp_poly
			(pts
				(xy 2.667 2.159) (xy -2.667 2.159) (xy -2.667 -2.159) (xy 2.667 -2.159)
			)
			(stroke
				(width 0)
				(type default)
			)
			(fill no)
			(layer "B.CrtYd")
		)
		(fp_line
			(start -1.8034 -1.2954)
			(end 1.8034 -1.2954)
			(stroke
				(width 0.1524)
				(type default)
			)
			(layer "B.Fab")
		)
		(fp_line
			(start -1.8034 1.2954)
			(end -1.8034 -1.2954)
			(stroke
				(width 0.1524)
				(type default)
			)
			(layer "B.Fab")
		)
		(fp_line
			(start 1.8034 -1.2954)
			(end 1.8034 1.2954)
			(stroke
				(width 0.1524)
				(type default)
			)
			(layer "B.Fab")
		)
		(fp_line
			(start 1.8034 1.2954)
			(end -1.8034 1.2954)
			(stroke
				(width 0.1524)
				(type default)
			)
			(layer "B.Fab")
		)
		(fp_circle
			(center 1.27 0.762)
			(end 1.553997 0.762)
			(stroke
				(width 0.1524)
				(type default)
			)
			(fill no)
			(layer "B.Fab")
		)
		(fp_text user "9"
			(at -2.3749 -0.472872 0)
			(unlocked yes)
			(layer "B.SilkS")
			(effects
				(font
					(size 0.7874 0.5842)
					(thickness 0.127)
				)
				(justify left mirror)
			)
		)
		(fp_text user "8"
			(at -2.3749 0.670154 0)
			(unlocked yes)
			(layer "B.SilkS")
			(effects
				(font
					(size 0.7874 0.5842)
					(thickness 0.127)
				)
				(justify left mirror)
			)
		)
		(fp_text user "10"
			(at -2.159 -1.75133 0)
			(unlocked yes)
			(layer "B.SilkS")
			(effects
				(font
					(size 0.7874 0.5842)
					(thickness 0.127)
				)
				(justify left mirror)
			)
		)
		(fp_text user "7"
			(at -2.159 1.67767 0)
			(unlocked yes)
			(layer "B.SilkS")
			(effects
				(font
					(size 0.7874 0.5842)
					(thickness 0.127)
				)
				(justify left mirror)
			)
		)
		(fp_text user "1"
			(at 2.667 0.53467 0)
			(unlocked yes)
			(layer "B.SilkS")
			(effects
				(font
					(size 0.7874 0.5842)
					(thickness 0.127)
				)
				(justify left mirror)
			)
		)
		(fp_text user "2"
			(at 2.921 2.18567 0)
			(unlocked yes)
			(layer "B.SilkS")
			(effects
				(font
					(size 0.7874 0.5842)
					(thickness 0.127)
				)
				(justify left mirror)
			)
		)
		(fp_text user "15"
			(at 3.048 -2.25933 0)
			(unlocked yes)
			(layer "B.SilkS")
			(effects
				(font
					(size 0.7874 0.5842)
					(thickness 0.127)
				)
				(justify left mirror)
			)
		)
		(fp_text user "16"
			(at 3.52933 -0.381 270)
			(unlocked yes)
			(layer "B.SilkS")
			(effects
				(font
					(size 0.7874 0.5842)
					(thickness 0.127)
				)
				(justify left mirror)
			)
		)
		(pad "1" smd custom
			(at 1.7018 0.250012 270)
			(size 0.06985 0.06985)
			(layers "B.Cu" "B.Mask" "B.Paste")
			(net "13N4351")
			(options
				(clearance outline)
				(anchor circle)
			)
			(primitives
				(gr_poly
					(pts
						(xy 0.1397 -0.4064)
						(arc
							(start 0.1397 0.2667)
							(mid 0 0.4064)
							(end -0.1397 0.2667)
						)
						(xy -0.1397 -0.4064)
					)
					(width 0)
					(fill yes)
				)
			)
		)
		(pad "2" smd custom
			(at 1.25001 1.1938 180)
			(size 0.06985 0.06985)
			(layers "B.Cu" "B.Mask" "B.Paste")
			(net "_NC_U21_74CBTLV_1B1")
			(options
				(clearance outline)
				(anchor circle)
			)
			(primitives
				(gr_poly
					(pts
						(xy 0.1397 -0.4064)
						(arc
							(start 0.1397 0.2667)
							(mid 0 0.4064)
							(end -0.1397 0.2667)
						)
						(xy -0.1397 -0.4064)
					)
					(width 0)
					(fill yes)
				)
			)
		)
		(pad "3" smd custom
			(at 0.750011 1.1938 180)
			(size 0.06985 0.06985)
			(layers "B.Cu" "B.Mask" "B.Paste")
			(net "MUX_NFP_GPIO0_NWK0_I2C_SCL")
			(options
				(clearance outline)
				(anchor circle)
			)
			(primitives
				(gr_poly
					(pts
						(xy 0.1397 -0.4064)
						(arc
							(start 0.1397 0.2667)
							(mid 0 0.4064)
							(end -0.1397 0.2667)
						)
						(xy -0.1397 -0.4064)
					)
					(width 0)
					(fill yes)
				)
			)
		)
		(pad "4" smd custom
			(at 0.250012 1.1938 180)
			(size 0.06985 0.06985)
			(layers "B.Cu" "B.Mask" "B.Paste")
			(net "NWK0_I2C_SCL")
			(options
				(clearance outline)
				(anchor circle)
			)
			(primitives
				(gr_poly
					(pts
						(xy 0.1397 -0.4064)
						(arc
							(start 0.1397 0.2667)
							(mid 0 0.4064)
							(end -0.1397 0.2667)
						)
						(xy -0.1397 -0.4064)
					)
					(width 0)
					(fill yes)
				)
			)
		)
		(pad "5" smd custom
			(at -0.250012 1.1938 180)
			(size 0.06985 0.06985)
			(layers "B.Cu" "B.Mask" "B.Paste")
			(net "_NC_U21_74CBTLV_2B1")
			(options
				(clearance outline)
				(anchor circle)
			)
			(primitives
				(gr_poly
					(pts
						(xy 0.1397 -0.4064)
						(arc
							(start 0.1397 0.2667)
							(mid 0 0.4064)
							(end -0.1397 0.2667)
						)
						(xy -0.1397 -0.4064)
					)
					(width 0)
					(fill yes)
				)
			)
		)
		(pad "6" smd custom
			(at -0.750011 1.1938 180)
			(size 0.06985 0.06985)
			(layers "B.Cu" "B.Mask" "B.Paste")
			(net "MUX_NFP_GPIO1_NWK0_I2C_SDA")
			(options
				(clearance outline)
				(anchor circle)
			)
			(primitives
				(gr_poly
					(pts
						(xy 0.1397 -0.4064)
						(arc
							(start 0.1397 0.2667)
							(mid 0 0.4064)
							(end -0.1397 0.2667)
						)
						(xy -0.1397 -0.4064)
					)
					(width 0)
					(fill yes)
				)
			)
		)
		(pad "7" smd custom
			(at -1.25001 1.1938 180)
			(size 0.06985 0.06985)
			(layers "B.Cu" "B.Mask" "B.Paste")
			(net "NWK0_I2C_SDA")
			(options
				(clearance outline)
				(anchor circle)
			)
			(primitives
				(gr_poly
					(pts
						(xy 0.1397 -0.4064)
						(arc
							(start 0.1397 0.2667)
							(mid 0 0.4064)
							(end -0.1397 0.2667)
						)
						(xy -0.1397 -0.4064)
					)
					(width 0)
					(fill yes)
				)
			)
		)
		(pad "8" smd custom
			(at -1.7018 0.250012 90)
			(size 0.06985 0.06985)
			(layers "B.Cu" "B.Mask" "B.Paste")
			(net "GND")
			(options
				(clearance outline)
				(anchor circle)
			)
			(primitives
				(gr_poly
					(pts
						(xy 0.1397 -0.4064)
						(arc
							(start 0.1397 0.2667)
							(mid 0 0.4064)
							(end -0.1397 0.2667)
						)
						(xy -0.1397 -0.4064)
					)
					(width 0)
					(fill yes)
				)
			)
		)
		(pad "9" smd custom
			(at -1.7018 -0.250012 90)
			(size 0.06985 0.06985)
			(layers "B.Cu" "B.Mask" "B.Paste")
			(net "NWK1_I2C_SCL")
			(options
				(clearance outline)
				(anchor circle)
			)
			(primitives
				(gr_poly
					(pts
						(xy 0.1397 -0.4064)
						(arc
							(start 0.1397 0.2667)
							(mid 0 0.4064)
							(end -0.1397 0.2667)
						)
						(xy -0.1397 -0.4064)
					)
					(width 0)
					(fill yes)
				)
			)
		)
		(pad "10" smd custom
			(at -1.25001 -1.1938)
			(size 0.06985 0.06985)
			(layers "B.Cu" "B.Mask" "B.Paste")
			(net "MUX_NFP_GPIO2_NWK1_I2C_SCL")
			(options
				(clearance outline)
				(anchor circle)
			)
			(primitives
				(gr_poly
					(pts
						(xy 0.1397 -0.4064)
						(arc
							(start 0.1397 0.2667)
							(mid 0 0.4064)
							(end -0.1397 0.2667)
						)
						(xy -0.1397 -0.4064)
					)
					(width 0)
					(fill yes)
				)
			)
		)
		(pad "11" smd custom
			(at -0.750011 -1.1938)
			(size 0.06985 0.06985)
			(layers "B.Cu" "B.Mask" "B.Paste")
			(net "_NC_U21_74CBTLV_3B1")
			(options
				(clearance outline)
				(anchor circle)
			)
			(primitives
				(gr_poly
					(pts
						(xy 0.1397 -0.4064)
						(arc
							(start 0.1397 0.2667)
							(mid 0 0.4064)
							(end -0.1397 0.2667)
						)
						(xy -0.1397 -0.4064)
					)
					(width 0)
					(fill yes)
				)
			)
		)
		(pad "12" smd custom
			(at -0.250012 -1.1938)
			(size 0.06985 0.06985)
			(layers "B.Cu" "B.Mask" "B.Paste")
			(net "NWK1_I2C_SDA")
			(options
				(clearance outline)
				(anchor circle)
			)
			(primitives
				(gr_poly
					(pts
						(xy 0.1397 -0.4064)
						(arc
							(start 0.1397 0.2667)
							(mid 0 0.4064)
							(end -0.1397 0.2667)
						)
						(xy -0.1397 -0.4064)
					)
					(width 0)
					(fill yes)
				)
			)
		)
		(pad "13" smd custom
			(at 0.250012 -1.1938)
			(size 0.06985 0.06985)
			(layers "B.Cu" "B.Mask" "B.Paste")
			(net "MUX_NFP_GPIO3_NWK1_I2C_SDA")
			(options
				(clearance outline)
				(anchor circle)
			)
			(primitives
				(gr_poly
					(pts
						(xy 0.1397 -0.4064)
						(arc
							(start 0.1397 0.2667)
							(mid 0 0.4064)
							(end -0.1397 0.2667)
						)
						(xy -0.1397 -0.4064)
					)
					(width 0)
					(fill yes)
				)
			)
		)
		(pad "14" smd custom
			(at 0.750011 -1.1938)
			(size 0.06985 0.06985)
			(layers "B.Cu" "B.Mask" "B.Paste")
			(net "_NC_U21_74CBTLV_4B1")
			(options
				(clearance outline)
				(anchor circle)
			)
			(primitives
				(gr_poly
					(pts
						(xy 0.1397 -0.4064)
						(arc
							(start 0.1397 0.2667)
							(mid 0 0.4064)
							(end -0.1397 0.2667)
						)
						(xy -0.1397 -0.4064)
					)
					(width 0)
					(fill yes)
				)
			)
		)
		(pad "15" smd custom
			(at 1.25001 -1.1938)
			(size 0.06985 0.06985)
			(layers "B.Cu" "B.Mask" "B.Paste")
			(net "13N4347")
			(options
				(clearance outline)
				(anchor circle)
			)
			(primitives
				(gr_poly
					(pts
						(xy 0.1397 -0.4064)
						(arc
							(start 0.1397 0.2667)
							(mid 0 0.4064)
							(end -0.1397 0.2667)
						)
						(xy -0.1397 -0.4064)
					)
					(width 0)
					(fill yes)
				)
			)
		)
		(pad "16" smd custom
			(at 1.7018 -0.250012 270)
			(size 0.06985 0.06985)
			(layers "B.Cu" "B.Mask" "B.Paste")
			(net "EXT_3.3V")
			(options
				(clearance outline)
				(anchor circle)
			)
			(primitives
				(gr_poly
					(pts
						(xy 0.1397 -0.4064)
						(arc
							(start 0.1397 0.2667)
							(mid 0 0.4064)
							(end -0.1397 0.2667)
						)
						(xy -0.1397 -0.4064)
					)
					(width 0)
					(fill yes)
				)
			)
		)
		(pad "17" smd rect
			(at 0 0 180)
			(size 1.9812 0.9652)
			(layers "B.Cu" "B.Mask" "B.Paste")
			(net "GND")
		)
		(zone
			(layer "B.Cu")
			(hatch none 0.5)
			(connect_pads
				(clearance 0)
			)
			(min_thickness 0.25)
			(keepout
				(tracks allowed)
				(vias not_allowed)
				(pads allowed)
				(copperpour not_allowed)
				(footprints allowed)
			)
			(placement
				(enabled no)
				(sheetname "")
			)
			(fill
				(thermal_gap 0.5)
				(thermal_bridge_width 0.5)
				(island_removal_mode 0)
			)
			(polygon
				(pts
					(arc
						(start 4.9022 15.875)
						(mid 4.2418 15.875)
						(end 4.9022 15.875)
					)
				)
			)
		)
	)
	(footprint ""
		(layer "B.Cu")
		(at 46.237017 9.542018)
		(property "Reference" "R319"
			(at 0 0 0)
			(layer "B.SilkS")
			(hide yes)
			(effects
				(font
					(size 1.27 1.27)
				)
				(justify mirror)
			)
		)
		(property "Value" ""
			(at 0 0 0)
			(layer "B.Fab")
			(effects
				(font
					(size 1.27 1.27)
				)
				(justify mirror)
			)
		)
		(duplicate_pad_numbers_are_jumpers no)
		(fp_circle
			(center 0 0)
			(end 0.104648 0)
			(stroke
				(width 0.1016)
				(type default)
			)
			(fill no)
			(layer "B.SilkS")
		)
		(fp_poly
			(pts
				(xy 0.381 -0.889) (xy 0.381 0.889) (xy -0.381 0.889) (xy -0.381 -0.889)
			)
			(stroke
				(width 0)
				(type default)
			)
			(fill no)
			(layer "B.CrtYd")
		)
		(fp_line
			(start -0.508 -1.016)
			(end -0.508 1.016)
			(stroke
				(width 0.0254)
				(type default)
			)
			(layer "B.Fab")
		)
		(fp_line
			(start -0.508 1.016)
			(end 0.508 1.016)
			(stroke
				(width 0.0254)
				(type default)
			)
			(layer "B.Fab")
		)
		(fp_line
			(start 0.254 -1.016)
			(end -0.508 -1.016)
			(stroke
				(width 0.0254)
				(type default)
			)
			(layer "B.Fab")
		)
		(fp_line
			(start 0.508 -1.016)
			(end 0.254 -1.016)
			(stroke
				(width 0.0254)
				(type default)
			)
			(layer "B.Fab")
		)
		(fp_line
			(start 0.508 1.016)
			(end 0.508 -1.016)
			(stroke
				(width 0.0254)
				(type default)
			)
			(layer "B.Fab")
		)
		(pad "1" smd custom
			(at 0 -0.500126 180)
			(size 0.127 0.127)
			(layers "B.Cu" "B.Mask" "B.Paste")
			(net "GND")
			(options
				(clearance outline)
				(anchor circle)
			)
			(primitives
				(gr_poly
					(pts
						(xy -0.1778 0.254) (xy 0.1778 0.254) (xy 0.254 0.1778) (xy 0.254 -0.1778) (xy 0.1778 -0.254) (xy -0.1778 -0.254)
						(xy -0.254 -0.1778) (xy -0.254 0.1778)
					)
					(width 0)
					(fill yes)
				)
			)
		)
		(pad "2" smd custom
			(at 0 0.500126 180)
			(size 0.127 0.127)
			(layers "B.Cu" "B.Mask" "B.Paste")
			(net "NFP_SERDES012_SYSCLK_IN_P")
			(options
				(clearance outline)
				(anchor circle)
			)
			(primitives
				(gr_poly
					(pts
						(xy -0.1778 0.254) (xy 0.1778 0.254) (xy 0.254 0.1778) (xy 0.254 -0.1778) (xy 0.1778 -0.254) (xy -0.1778 -0.254)
						(xy -0.254 -0.1778) (xy -0.254 0.1778)
					)
					(width 0)
					(fill yes)
				)
			)
		)
	)
	(footprint ""
		(layer "B.Cu")
		(at 81.850992 6.698996)
		(property "Reference" "V1_A-A12"
			(at 0 0 0)
			(layer "B.SilkS")
			(hide yes)
			(effects
				(font
					(size 1.27 1.27)
				)
				(justify mirror)
			)
		)
		(property "Value" ""
			(at 0 0 0)
			(layer "B.Fab")
			(effects
				(font
					(size 1.27 1.27)
				)
				(justify mirror)
			)
		)
		(duplicate_pad_numbers_are_jumpers no)
		(pad "1" thru_hole circle
			(at 0 0 180)
			(size 0.4572 0.4572)
			(drill 0.20574)
			(layers "*.Cu" "*.Mask")
			(remove_unused_layers no)
			(net "DDR0_32A_A12")
			(clearance 0.1143)
			(thermal_gap 0.1143)
		)
	)
	(footprint ""
		(layer "B.Cu")
		(at 81.050994 1.899006)
		(property "Reference" "V1_A-BA0"
			(at 0 0 0)
			(layer "B.SilkS")
			(hide yes)
			(effects
				(font
					(size 1.27 1.27)
				)
				(justify mirror)
			)
		)
		(property "Value" ""
			(at 0 0 0)
			(layer "B.Fab")
			(effects
				(font
					(size 1.27 1.27)
				)
				(justify mirror)
			)
		)
		(duplicate_pad_numbers_are_jumpers no)
		(pad "1" thru_hole circle
			(at 0 0 180)
			(size 0.4572 0.4572)
			(drill 0.20574)
			(layers "*.Cu" "*.Mask")
			(remove_unused_layers no)
			(net "DDR0_32A_BA0")
			(clearance 0.1143)
			(thermal_gap 0.1143)
		)
	)
	(footprint ""
		(layer "B.Cu")
		(at 51.237007 12.542012)
		(property "Reference" "C77"
			(at -0.463677 2.316988 270)
			(unlocked yes)
			(layer "B.SilkS")
			(effects
				(font
					(size 0.7874 0.5842)
					(thickness 0.127)
				)
				(justify mirror)
			)
		)
		(property "Value" ""
			(at 0 0 0)
			(layer "B.Fab")
			(effects
				(font
					(size 1.27 1.27)
				)
				(justify mirror)
			)
		)
		(duplicate_pad_numbers_are_jumpers no)
		(fp_circle
			(center 0 0)
			(end 0.104648 0)
			(stroke
				(width 0.1016)
				(type default)
			)
			(fill no)
			(layer "B.SilkS")
		)
		(fp_poly
			(pts
				(xy 0.381 -0.889) (xy 0.381 0.889) (xy -0.381 0.889) (xy -0.381 -0.889)
			)
			(stroke
				(width 0)
				(type default)
			)
			(fill no)
			(layer "B.CrtYd")
		)
		(fp_line
			(start -0.508 -1.016)
			(end -0.508 1.016)
			(stroke
				(width 0.0254)
				(type default)
			)
			(layer "B.Fab")
		)
		(fp_line
			(start -0.508 1.016)
			(end 0.508 1.016)
			(stroke
				(width 0.0254)
				(type default)
			)
			(layer "B.Fab")
		)
		(fp_line
			(start 0.254 -1.016)
			(end -0.508 -1.016)
			(stroke
				(width 0.0254)
				(type default)
			)
			(layer "B.Fab")
		)
		(fp_line
			(start 0.508 -1.016)
			(end 0.254 -1.016)
			(stroke
				(width 0.0254)
				(type default)
			)
			(layer "B.Fab")
		)
		(fp_line
			(start 0.508 1.016)
			(end 0.508 -1.016)
			(stroke
				(width 0.0254)
				(type default)
			)
			(layer "B.Fab")
		)
		(pad "1" smd custom
			(at 0 -0.500126 180)
			(size 0.127 0.127)
			(layers "B.Cu" "B.Mask" "B.Paste")
			(net "VDD_CORE")
			(options
				(clearance outline)
				(anchor circle)
			)
			(primitives
				(gr_poly
					(pts
						(xy -0.1778 0.254) (xy 0.1778 0.254) (xy 0.254 0.1778) (xy 0.254 -0.1778) (xy 0.1778 -0.254) (xy -0.1778 -0.254)
						(xy -0.254 -0.1778) (xy -0.254 0.1778)
					)
					(width 0)
					(fill yes)
				)
			)
		)
		(pad "2" smd custom
			(at 0 0.500126 180)
			(size 0.127 0.127)
			(layers "B.Cu" "B.Mask" "B.Paste")
			(net "GND")
			(options
				(clearance outline)
				(anchor circle)
			)
			(primitives
				(gr_poly
					(pts
						(xy -0.1778 0.254) (xy 0.1778 0.254) (xy 0.254 0.1778) (xy 0.254 -0.1778) (xy 0.1778 -0.254) (xy -0.1778 -0.254)
						(xy -0.254 -0.1778) (xy -0.254 0.1778)
					)
					(width 0)
					(fill yes)
				)
			)
		)
	)
	(footprint ""
		(layer "B.Cu")
		(at 82.65099 25.813004)
		(property "Reference" "V3_A-A02"
			(at 0 0 0)
			(layer "B.SilkS")
			(hide yes)
			(effects
				(font
					(size 1.27 1.27)
				)
				(justify mirror)
			)
		)
		(property "Value" ""
			(at 0 0 0)
			(layer "B.Fab")
			(effects
				(font
					(size 1.27 1.27)
				)
				(justify mirror)
			)
		)
		(duplicate_pad_numbers_are_jumpers no)
		(pad "1" thru_hole circle
			(at 0 0 180)
			(size 0.4572 0.4572)
			(drill 0.20574)
			(layers "*.Cu" "*.Mask")
			(remove_unused_layers no)
			(net "DDR0_32A_A2")
			(clearance 0.1143)
			(thermal_gap 0.1143)
		)
	)
)
